FILE_TYPE = MULTI_PHYS_TABLE;

PART 'SCONN67_NASA0S6730TS67'

{========================================================================================}
:VALUE                      | PART_TYPE | MATERIAL | PART_NUMBER    = STANDARD | LIFECYCLE     | PART_NUMBER   | JEDEC_TYPE                       | DESCRIPTION                             | MANUFTR | MANUF_PN           | RD_CMPLS_LVL | CMPLS_LVL | CLASS | DIP_SMD | FROM_PJ    | DATA                       | FP_ECN                 | EE_CHECK_LIST | CREATOR | CREATEDAY  | PSL | STATUS | ESD_CDM | ESD_HBM | ESD_MM | MSD  | PIN_LENGTH_LONG_PIN | PIN_LENGTH_SHORT_PIN ;
{========================================================================================}
 'SCONN67_NASA0-S6730-TS67' | 'SMLF'    | 'IO'     | 'DFHS75FR133'(!) = ''       | ''               | 'DFHS75FR133' |'CON_F67S2H2D2S_P0-5W7-55_LUVXM'| 'CONN SMD HOUSING 75P 2R FR(P0.5,H6.7)' | 'LTK'   | 'NASA0-S6730-TS67' | 'EP(V1)'     | ''        | 'IO'  | ''      | 'F0G-BELL' | 'LTK_NASA0-S6730-TS67.pdf' | 'NASA0-S6730-TS67.msg' | ''            | ''      | '20191002' | ''  | ''     | 'NA'    | 'NA'    | 'NA'   | 'NA' | '30 MILS'           | '30 MILS'           
 'SCONN67_NASA0-S6730-TS67' | 'SMLF'    | 'EMPTY'  | 'DFHS75FR133'(!) = ''       | ''               | 'DFHS75FR133' |'CON_F67S2H2D2S_P0-5W7-55_LUVXM'| 'CONN SMD HOUSING 75P 2R FR(P0.5,H6.7)' | 'LTK'   | 'NASA0-S6730-TS67' | 'EP(V1)'     | ''        | 'IO'  | ''      | 'F0G-BELL' | 'LTK_NASA0-S6730-TS67.pdf' | 'NASA0-S6730-TS67.msg' | ''            | ''      | '20191002' | ''  | ''     | 'NA'    | 'NA'    | 'NA'   | 'NA' | '30 MILS'           | '30 MILS'           

END_PART

END.

